(kicad_pcb
	(version 20260206)
	(generator "pcbnew")
	(generator_version "10.0")
	(general
		(thickness 1.6)
		(legacy_teardrops no)
	)
	(paper "A4")
	(title_block
		(title "01162023_DA0F0TEBIF0_F0T_Expander_BD_F_brd_V02_OCP.brd")
		(comment 1 "Grand Teton / footprints 5563-5568 of 9728")
	)
	(layers
		(0 "F.Cu" signal "TOP")
		(4 "In1.Cu" signal "GND")
		(6 "In2.Cu" signal "VCC")
		(8 "In3.Cu" signal "VCC1")
		(10 "In4.Cu" signal "GND1")
		(12 "In5.Cu" signal "IN1")
		(14 "In6.Cu" signal "GND2")
		(16 "In7.Cu" signal "IN2")
		(18 "In8.Cu" signal "GND3")
		(20 "In9.Cu" signal "IN3")
		(22 "In10.Cu" signal "GND4")
		(24 "In11.Cu" signal "IN4")
		(26 "In12.Cu" signal "GND5")
		(28 "In13.Cu" signal "IN5")
		(30 "In14.Cu" signal "GND6")
		(32 "In15.Cu" signal "IN6")
		(34 "In16.Cu" signal "GND7")
		(2 "B.Cu" signal "BOTTOM")
		(9 "F.Adhes" user "F.Adhesive")
		(11 "B.Adhes" user "B.Adhesive")
		(13 "F.Paste" user "Package Geometry/Pastemask Top")
		(15 "B.Paste" user "Package Geometry/Pastemask Bottom")
		(5 "F.SilkS" user "Ref Des/Silkscreen Top")
		(7 "B.SilkS" user "Ref Des/Silkscreen Bottom")
		(1 "F.Mask" user "Board Geometry/Soldermask Top")
		(3 "B.Mask" user "Board Geometry/Soldermask Bottom")
		(17 "Dwgs.User" user "User.Drawings")
		(19 "Cmts.User" user "User.Comments")
		(21 "Eco1.User" user "User.Eco1")
		(23 "Eco2.User" user "User.Eco2")
		(25 "Edge.Cuts" user "Board Geometry/Outline")
		(27 "Margin" user)
		(31 "F.CrtYd" user "Package Geometry/Place Bound Top")
		(29 "B.CrtYd" user "Package Geometry/Place Bound Bottom")
		(35 "F.Fab" user "Ref Des/Assembly Top")
		(33 "B.Fab" user "Ref Des/Assembly Bottom")
	)
	(footprint ""
		(layer "F.Cu")
		(at 354.952808 -156.288994 -90)
		(property "Reference" "PR7045"
			(at 0 0 270)
			(layer "F.SilkS")
			(hide yes)
			(effects
				(font
					(size 1.27 1.27)
				)
			)
		)
		(property "Value" ""
			(at 0 0 270)
			(layer "F.Fab")
			(effects
				(font
					(size 1.27 1.27)
				)
			)
		)
		(duplicate_pad_numbers_are_jumpers no)
		(fp_line
			(start -0.7874 0.4064)
			(end -0.7874 -0.4064)
			(stroke
				(width 0.1524)
				(type default)
			)
			(layer "F.SilkS")
		)
		(fp_line
			(start 0.7874 0.4064)
			(end -0.7874 0.4064)
			(stroke
				(width 0.1524)
				(type default)
			)
			(layer "F.SilkS")
		)
		(fp_line
			(start -0.7874 -0.4064)
			(end 0.7874 -0.4064)
			(stroke
				(width 0.1524)
				(type default)
			)
			(layer "F.SilkS")
		)
		(fp_line
			(start 0.7874 -0.4064)
			(end 0.7874 0.4064)
			(stroke
				(width 0.1524)
				(type default)
			)
			(layer "F.SilkS")
		)
		(fp_line
			(start -0.67945 0.3048)
			(end -0.67945 -0.305054)
			(stroke
				(width 0.1)
				(type default)
			)
			(layer "F.Fab")
		)
		(fp_line
			(start -0.12065 0.3048)
			(end -0.67945 0.3048)
			(stroke
				(width 0.1)
				(type default)
			)
			(layer "F.Fab")
		)
		(fp_line
			(start 0.120396 0.3048)
			(end 0.120396 0.2794)
			(stroke
				(width 0.1)
				(type default)
			)
			(layer "F.Fab")
		)
		(fp_line
			(start 0.67945 0.3048)
			(end 0.120396 0.3048)
			(stroke
				(width 0.1)
				(type default)
			)
			(layer "F.Fab")
		)
		(fp_line
			(start -0.12065 0.2794)
			(end -0.12065 0.3048)
			(stroke
				(width 0.1)
				(type default)
			)
			(layer "F.Fab")
		)
		(fp_line
			(start 0.120396 0.2794)
			(end -0.12065 0.2794)
			(stroke
				(width 0.1)
				(type default)
			)
			(layer "F.Fab")
		)
		(fp_line
			(start -0.12065 -0.2794)
			(end 0.12065 -0.2794)
			(stroke
				(width 0.1)
				(type default)
			)
			(layer "F.Fab")
		)
		(fp_line
			(start 0.12065 -0.2794)
			(end 0.12065 -0.3048)
			(stroke
				(width 0.1)
				(type default)
			)
			(layer "F.Fab")
		)
		(fp_line
			(start 0.12065 -0.3048)
			(end 0.67945 -0.3048)
			(stroke
				(width 0.1)
				(type default)
			)
			(layer "F.Fab")
		)
		(fp_line
			(start 0.67945 -0.3048)
			(end 0.67945 0.3048)
			(stroke
				(width 0.1)
				(type default)
			)
			(layer "F.Fab")
		)
		(fp_line
			(start -0.67945 -0.305054)
			(end -0.12065 -0.305054)
			(stroke
				(width 0.1)
				(type default)
			)
			(layer "F.Fab")
		)
		(fp_line
			(start -0.12065 -0.305054)
			(end -0.12065 -0.2794)
			(stroke
				(width 0.1)
				(type default)
			)
			(layer "F.Fab")
		)
		(pad "1" smd circle
			(at -0.40005 0 270)
			(size 0 0)
			(layers "F.Cu" "F.Mask" "F.Paste")
			(net "P12V_NIC6_CO_OV_FB")
		)
		(pad "2" smd circle
			(at 0.40005 0 270)
			(size 0 0)
			(layers "F.Cu" "F.Mask" "F.Paste")
			(net "P12V_NIC6_R")
		)
	)
	(footprint ""
		(layer "F.Cu")
		(at 222.180912 -201.733658)
		(property "Reference" "R5281"
			(at 0 0 0)
			(layer "F.SilkS")
			(hide yes)
			(effects
				(font
					(size 1.27 1.27)
				)
			)
		)
		(property "Value" ""
			(at 0 0 0)
			(layer "F.Fab")
			(effects
				(font
					(size 1.27 1.27)
				)
			)
		)
		(duplicate_pad_numbers_are_jumpers no)
		(fp_line
			(start -0.7874 -0.4064)
			(end 0.7874 -0.4064)
			(stroke
				(width 0.1524)
				(type default)
			)
			(layer "F.SilkS")
		)
		(fp_line
			(start -0.7874 0.4064)
			(end -0.7874 -0.4064)
			(stroke
				(width 0.1524)
				(type default)
			)
			(layer "F.SilkS")
		)
		(fp_line
			(start 0.7874 -0.4064)
			(end 0.7874 0.4064)
			(stroke
				(width 0.1524)
				(type default)
			)
			(layer "F.SilkS")
		)
		(fp_line
			(start 0.7874 0.4064)
			(end -0.7874 0.4064)
			(stroke
				(width 0.1524)
				(type default)
			)
			(layer "F.SilkS")
		)
		(fp_line
			(start -0.67945 -0.305054)
			(end -0.12065 -0.305054)
			(stroke
				(width 0.1)
				(type default)
			)
			(layer "F.Fab")
		)
		(fp_line
			(start -0.67945 0.3048)
			(end -0.67945 -0.305054)
			(stroke
				(width 0.1)
				(type default)
			)
			(layer "F.Fab")
		)
		(fp_line
			(start -0.12065 -0.305054)
			(end -0.12065 -0.2794)
			(stroke
				(width 0.1)
				(type default)
			)
			(layer "F.Fab")
		)
		(fp_line
			(start -0.12065 -0.2794)
			(end 0.12065 -0.2794)
			(stroke
				(width 0.1)
				(type default)
			)
			(layer "F.Fab")
		)
		(fp_line
			(start -0.12065 0.2794)
			(end -0.12065 0.3048)
			(stroke
				(width 0.1)
				(type default)
			)
			(layer "F.Fab")
		)
		(fp_line
			(start -0.12065 0.3048)
			(end -0.67945 0.3048)
			(stroke
				(width 0.1)
				(type default)
			)
			(layer "F.Fab")
		)
		(fp_line
			(start 0.120396 0.2794)
			(end -0.12065 0.2794)
			(stroke
				(width 0.1)
				(type default)
			)
			(layer "F.Fab")
		)
		(fp_line
			(start 0.120396 0.3048)
			(end 0.120396 0.2794)
			(stroke
				(width 0.1)
				(type default)
			)
			(layer "F.Fab")
		)
		(fp_line
			(start 0.12065 -0.3048)
			(end 0.67945 -0.3048)
			(stroke
				(width 0.1)
				(type default)
			)
			(layer "F.Fab")
		)
		(fp_line
			(start 0.12065 -0.2794)
			(end 0.12065 -0.3048)
			(stroke
				(width 0.1)
				(type default)
			)
			(layer "F.Fab")
		)
		(fp_line
			(start 0.67945 -0.3048)
			(end 0.67945 0.3048)
			(stroke
				(width 0.1)
				(type default)
			)
			(layer "F.Fab")
		)
		(fp_line
			(start 0.67945 0.3048)
			(end 0.120396 0.3048)
			(stroke
				(width 0.1)
				(type default)
			)
			(layer "F.Fab")
		)
		(pad "1" smd circle
			(at -0.40005 0)
			(size 0 0)
			(layers "F.Cu" "F.Mask" "F.Paste")
			(net "GND")
		)
		(pad "2" smd circle
			(at 0.40005 0)
			(size 0 0)
			(layers "F.Cu" "F.Mask" "F.Paste")
			(net "JTAG_BIC_NTRST_R_N")
		)
	)
	(footprint ""
		(layer "F.Cu")
		(at 194.234308 -87.599012)
		(property "Reference" "U25"
			(at -0.991108 -1.706118 0)
			(unlocked yes)
			(layer "F.SilkS")
			(effects
				(font
					(size 0.7874 0.5842)
					(thickness 0.1524)
				)
				(justify left)
			)
		)
		(property "Value" ""
			(at 0 0 0)
			(layer "F.Fab")
			(effects
				(font
					(size 1.27 1.27)
				)
			)
		)
		(duplicate_pad_numbers_are_jumpers no)
		(fp_line
			(start -1.684274 -1.074928)
			(end -0.381 -1.074928)
			(stroke
				(width 0.1524)
				(type default)
			)
			(layer "F.SilkS")
		)
		(fp_line
			(start -1.684274 1.074928)
			(end -1.684274 -1.074928)
			(stroke
				(width 0.1524)
				(type default)
			)
			(layer "F.SilkS")
		)
		(fp_line
			(start -0.381 -1.074928)
			(end 0 -0.625094)
			(stroke
				(width 0.1524)
				(type default)
			)
			(layer "F.SilkS")
		)
		(fp_line
			(start 0 -0.625094)
			(end 0.381 -1.074928)
			(stroke
				(width 0.1524)
				(type default)
			)
			(layer "F.SilkS")
		)
		(fp_line
			(start 0.381 -1.074928)
			(end 1.684274 -1.074928)
			(stroke
				(width 0.1524)
				(type default)
			)
			(layer "F.SilkS")
		)
		(fp_line
			(start 1.684274 -1.074928)
			(end 1.684274 1.074928)
			(stroke
				(width 0.1524)
				(type default)
			)
			(layer "F.SilkS")
		)
		(fp_line
			(start 1.684274 1.074928)
			(end -1.684274 1.074928)
			(stroke
				(width 0.1524)
				(type default)
			)
			(layer "F.SilkS")
		)
		(fp_poly
			(pts
				(xy -2.637282 -0.903986) (xy -2.637282 -0.395986) (xy -1.875282 -0.649986)
			)
			(stroke
				(width 0)
				(type default)
			)
			(fill yes)
			(layer "F.SilkS")
		)
		(fp_line
			(start -0.700024 -1.074928)
			(end -0.700024 1.074928)
			(stroke
				(width 0.1)
				(type default)
			)
			(layer "F.Fab")
		)
		(fp_line
			(start -0.700024 1.074928)
			(end 0.700024 1.074928)
			(stroke
				(width 0.1)
				(type default)
			)
			(layer "F.Fab")
		)
		(fp_line
			(start 0.700024 -1.074928)
			(end -0.700024 -1.074928)
			(stroke
				(width 0.1)
				(type default)
			)
			(layer "F.Fab")
		)
		(fp_line
			(start 0.700024 1.074928)
			(end 0.700024 -1.074928)
			(stroke
				(width 0.1)
				(type default)
			)
			(layer "F.Fab")
		)
		(fp_poly
			(pts
				(xy -2.637282 -0.903986) (xy -2.637282 -0.395986) (xy -1.875282 -0.649986)
			)
			(stroke
				(width 0)
				(type default)
			)
			(fill yes)
			(layer "F.Fab")
		)
		(pad "1" smd rect
			(at -1.100074 -0.649986 270)
			(size 0.4064 0.9144)
			(layers "F.Cu" "F.Mask" "F.Paste")
			(net "Net_8453")
		)
		(pad "2" smd rect
			(at -1.100074 0 270)
			(size 0.4064 0.9144)
			(layers "F.Cu" "F.Mask" "F.Paste")
			(net "RST_HP_NIC3_N")
		)
		(pad "3" smd rect
			(at -1.100074 0.649986 270)
			(size 0.4064 0.9144)
			(layers "F.Cu" "F.Mask" "F.Paste")
			(net "GND")
		)
		(pad "4" smd rect
			(at 1.100074 0.649986 270)
			(size 0.4064 0.9144)
			(layers "F.Cu" "F.Mask" "F.Paste")
			(net "RST_HP_NIC3_BUF_N")
		)
		(pad "5" smd rect
			(at 1.100074 -0.649986 270)
			(size 0.4064 0.9144)
			(layers "F.Cu" "F.Mask" "F.Paste")
			(net "P3V3_AUX")
		)
	)
	(footprint ""
		(layer "F.Cu")
		(at 329.457812 -72.766682 90)
		(property "Reference" "PC874"
			(at 0 0 90)
			(layer "F.SilkS")
			(hide yes)
			(effects
				(font
					(size 1.27 1.27)
				)
			)
		)
		(property "Value" ""
			(at 0 0 90)
			(layer "F.Fab")
			(effects
				(font
					(size 1.27 1.27)
				)
			)
		)
		(duplicate_pad_numbers_are_jumpers no)
		(fp_line
			(start 0.7874 -0.4064)
			(end 0.7874 0.4064)
			(stroke
				(width 0.1524)
				(type default)
			)
			(layer "F.SilkS")
		)
		(fp_line
			(start -0.7874 -0.4064)
			(end 0.7874 -0.4064)
			(stroke
				(width 0.1524)
				(type default)
			)
			(layer "F.SilkS")
		)
		(fp_line
			(start 0.7874 0.4064)
			(end -0.7874 0.4064)
			(stroke
				(width 0.1524)
				(type default)
			)
			(layer "F.SilkS")
		)
		(fp_line
			(start -0.7874 0.4064)
			(end -0.7874 -0.4064)
			(stroke
				(width 0.1524)
				(type default)
			)
			(layer "F.SilkS")
		)
		(fp_line
			(start -0.12065 -0.305054)
			(end -0.12065 -0.2794)
			(stroke
				(width 0.1)
				(type default)
			)
			(layer "F.Fab")
		)
		(fp_line
			(start -0.67945 -0.305054)
			(end -0.12065 -0.305054)
			(stroke
				(width 0.1)
				(type default)
			)
			(layer "F.Fab")
		)
		(fp_line
			(start 0.67945 -0.3048)
			(end 0.67945 0.3048)
			(stroke
				(width 0.1)
				(type default)
			)
			(layer "F.Fab")
		)
		(fp_line
			(start 0.12065 -0.3048)
			(end 0.67945 -0.3048)
			(stroke
				(width 0.1)
				(type default)
			)
			(layer "F.Fab")
		)
		(fp_line
			(start 0.12065 -0.2794)
			(end 0.12065 -0.3048)
			(stroke
				(width 0.1)
				(type default)
			)
			(layer "F.Fab")
		)
		(fp_line
			(start -0.12065 -0.2794)
			(end 0.12065 -0.2794)
			(stroke
				(width 0.1)
				(type default)
			)
			(layer "F.Fab")
		)
		(fp_line
			(start 0.120396 0.2794)
			(end -0.12065 0.2794)
			(stroke
				(width 0.1)
				(type default)
			)
			(layer "F.Fab")
		)
		(fp_line
			(start -0.12065 0.2794)
			(end -0.12065 0.3048)
			(stroke
				(width 0.1)
				(type default)
			)
			(layer "F.Fab")
		)
		(fp_line
			(start 0.67945 0.3048)
			(end 0.120396 0.3048)
			(stroke
				(width 0.1)
				(type default)
			)
			(layer "F.Fab")
		)
		(fp_line
			(start 0.120396 0.3048)
			(end 0.120396 0.2794)
			(stroke
				(width 0.1)
				(type default)
			)
			(layer "F.Fab")
		)
		(fp_line
			(start -0.12065 0.3048)
			(end -0.67945 0.3048)
			(stroke
				(width 0.1)
				(type default)
			)
			(layer "F.Fab")
		)
		(fp_line
			(start -0.67945 0.3048)
			(end -0.67945 -0.305054)
			(stroke
				(width 0.1)
				(type default)
			)
			(layer "F.Fab")
		)
		(pad "1" smd circle
			(at -0.40005 0 90)
			(size 0 0)
			(layers "F.Cu" "F.Mask" "F.Paste")
			(net "P12V_SSD11_CO_MODE")
		)
		(pad "2" smd circle
			(at 0.40005 0 90)
			(size 0 0)
			(layers "F.Cu" "F.Mask" "F.Paste")
			(net "GND")
		)
	)
	(footprint ""
		(layer "F.Cu")
		(at 381.191008 -55.663846 90)
		(property "Reference" "PU65"
			(at -1.1938 2.755392 90)
			(unlocked yes)
			(layer "F.SilkS")
			(effects
				(font
					(size 0.7874 0.5842)
					(thickness 0.1524)
				)
				(justify left)
			)
		)
		(property "Value" ""
			(at 0 0 90)
			(layer "F.Fab")
			(effects
				(font
					(size 1.27 1.27)
				)
			)
		)
		(duplicate_pad_numbers_are_jumpers no)
		(fp_line
			(start 1.943608 -1.549908)
			(end 1.943608 1.549908)
			(stroke
				(width 0.1524)
				(type default)
			)
			(layer "F.SilkS")
		)
		(fp_line
			(start -1.943608 -1.549908)
			(end 1.943608 -1.549908)
			(stroke
				(width 0.1524)
				(type default)
			)
			(layer "F.SilkS")
		)
		(fp_line
			(start 1.943608 1.549908)
			(end -1.943608 1.549908)
			(stroke
				(width 0.1524)
				(type default)
			)
			(layer "F.SilkS")
		)
		(fp_line
			(start -1.943608 1.549908)
			(end -1.943608 -1.549908)
			(stroke
				(width 0.1524)
				(type default)
			)
			(layer "F.SilkS")
		)
		(fp_poly
			(pts
				(xy -2.019808 -1.549908) (xy -1.257808 -1.549908) (xy -1.257808 -1.880108) (xy -2.019808 -1.880108)
			)
			(stroke
				(width 0)
				(type default)
			)
			(fill yes)
			(layer "F.SilkS")
		)
		(fp_line
			(start 1.549908 -1.549908)
			(end 1.549908 1.549908)
			(stroke
				(width 0.1)
				(type default)
			)
			(layer "F.Fab")
		)
		(fp_line
			(start -1.549908 -1.549908)
			(end 1.549908 -1.549908)
			(stroke
				(width 0.1)
				(type default)
			)
			(layer "F.Fab")
		)
		(fp_line
			(start 1.549908 1.549908)
			(end -1.549908 1.549908)
			(stroke
				(width 0.1)
				(type default)
			)
			(layer "F.Fab")
		)
		(fp_line
			(start -1.549908 1.549908)
			(end -1.549908 -1.549908)
			(stroke
				(width 0.1)
				(type default)
			)
			(layer "F.Fab")
		)
		(fp_poly
			(pts
				(xy -2.019808 -1.549908) (xy -1.257808 -1.549908) (xy -1.257808 -1.880108) (xy -2.019808 -1.880108)
			)
			(stroke
				(width 0)
				(type default)
			)
			(fill yes)
			(layer "F.Fab")
		)
		(pad "1" smd rect
			(at -1.500124 -1.249934)
			(size 0.2794 0.6096)
			(layers "F.Cu" "F.Mask" "F.Paste")
			(net "P3V3_SSD13")
		)
		(pad "2" smd rect
			(at -1.500124 -0.750062)
			(size 0.2794 0.6096)
			(layers "F.Cu" "F.Mask" "F.Paste")
			(net "P3V3_SSD13")
		)
		(pad "3" smd rect
			(at -1.500124 -0.249936)
			(size 0.2794 0.6096)
			(layers "F.Cu" "F.Mask" "F.Paste")
			(net "P3V3_SSD13")
		)
		(pad "4" smd rect
			(at -1.500124 0.249936)
			(size 0.2794 0.6096)
			(layers "F.Cu" "F.Mask" "F.Paste")
			(net "P3V3_SSD13")
		)
		(pad "5" smd rect
			(at -1.500124 0.750062)
			(size 0.2794 0.6096)
			(layers "F.Cu" "F.Mask" "F.Paste")
			(net "P3V3_SSD13")
		)
		(pad "6" smd rect
			(at -1.500124 1.249934)
			(size 0.2794 0.6096)
			(layers "F.Cu" "F.Mask" "F.Paste")
			(net "GND")
		)
		(pad "7" smd rect
			(at 1.500124 1.249934)
			(size 0.2794 0.6096)
			(layers "F.Cu" "F.Mask" "F.Paste")
			(net "P3V3_SSD13_SS")
		)
		(pad "8" smd rect
			(at 1.500124 0.750062)
			(size 0.2794 0.6096)
			(layers "F.Cu" "F.Mask" "F.Paste")
			(net "PWRGD_P3V3_SSD13")
		)
		(pad "9" smd rect
			(at 1.500124 0.249936)
			(size 0.2794 0.6096)
			(layers "F.Cu" "F.Mask" "F.Paste")
			(net "P3V3_SSD13_OCP")
		)
		(pad "10" smd rect
			(at 1.500124 -0.249936)
			(size 0.2794 0.6096)
			(layers "F.Cu" "F.Mask" "F.Paste")
			(net "P5V_AUX")
		)
		(pad "11" smd rect
			(at 1.500124 -0.750062)
			(size 0.2794 0.6096)
			(layers "F.Cu" "F.Mask" "F.Paste")
			(net "SSD13_AUX_P3V3_EN_R")
		)
		(pad "12" smd rect
			(at 1.500124 -1.249934)
			(size 0.2794 0.6096)
			(layers "F.Cu" "F.Mask" "F.Paste")
			(net "P3V3_AUX")
		)
		(pad "13" smd rect
			(at 0 0 90)
			(size 1.9812 2.7178)
			(layers "F.Cu" "F.Mask" "F.Paste")
			(net "P3V3_AUX")
		)
		(zone
			(layer "F.Cu")
			(hatch none 0.5)
			(connect_pads
				(clearance 0)
			)
			(min_thickness 0.25)
			(keepout
				(tracks not_allowed)
				(vias allowed)
				(pads allowed)
				(copperpour not_allowed)
				(footprints allowed)
			)
			(placement
				(enabled no)
				(sheetname "")
			)
			(fill
				(thermal_gap 0.5)
				(thermal_bridge_width 0.5)
				(island_removal_mode 0)
			)
			(polygon
				(pts
					(xy 379.641608 -56.806846) (xy 379.768608 -56.806846) (xy 382.740408 -56.806846) (xy 382.740916 -56.806846)
					(xy 382.740916 -54.520846) (xy 382.740408 -54.520846) (xy 382.613408 -54.520846) (xy 381.191008 -54.520846)
					(xy 381.191008 -54.622446) (xy 382.613408 -54.622446) (xy 382.613408 -56.705246) (xy 379.768608 -56.705246)
					(xy 379.768608 -54.622446) (xy 381.165608 -54.622446) (xy 381.165608 -54.520846) (xy 379.768608 -54.520846)
					(xy 379.641608 -54.520846) (xy 379.6411 -54.520846) (xy 379.6411 -56.806846)
				)
			)
		)
	)
	(footprint ""
		(layer "F.Cu")
		(at 108.007404 -166.252652 180)
		(property "Reference" "PC28"
			(at 0 0 180)
			(layer "F.SilkS")
			(hide yes)
			(effects
				(font
					(size 1.27 1.27)
				)
			)
		)
		(property "Value" ""
			(at 0 0 180)
			(layer "F.Fab")
			(effects
				(font
					(size 1.27 1.27)
				)
			)
		)
		(duplicate_pad_numbers_are_jumpers no)
		(fp_line
			(start 1.524 0.762)
			(end -1.524 0.762)
			(stroke
				(width 0.1524)
				(type default)
			)
			(layer "F.SilkS")
		)
		(fp_line
			(start 1.524 -0.762)
			(end 1.524 0.762)
			(stroke
				(width 0.1524)
				(type default)
			)
			(layer "F.SilkS")
		)
		(fp_line
			(start -1.524 0.762)
			(end -1.524 -0.762)
			(stroke
				(width 0.1524)
				(type default)
			)
			(layer "F.SilkS")
		)
		(fp_line
			(start -1.524 -0.762)
			(end 1.524 -0.762)
			(stroke
				(width 0.1524)
				(type default)
			)
			(layer "F.SilkS")
		)
		(fp_line
			(start 1.1049 0.724916)
			(end 1.1049 -0.724916)
			(stroke
				(width 0.1)
				(type default)
			)
			(layer "F.Fab")
		)
		(fp_line
			(start 1.1049 -0.724916)
			(end -1.1049 -0.724916)
			(stroke
				(width 0.1)
				(type default)
			)
			(layer "F.Fab")
		)
		(fp_line
			(start -1.1049 0.724916)
			(end 1.1049 0.724916)
			(stroke
				(width 0.1)
				(type default)
			)
			(layer "F.Fab")
		)
		(fp_line
			(start -1.1049 -0.724916)
			(end -1.1049 0.724916)
			(stroke
				(width 0.1)
				(type default)
			)
			(layer "F.Fab")
		)
		(pad "1" smd rect
			(at -0.889 0)
			(size 1.016 1.27)
			(layers "F.Cu" "F.Mask" "F.Paste")
			(net "SW_P12V_P3V3_AUX_FLT")
		)
		(pad "2" smd rect
			(at 0.889 0)
			(size 1.016 1.27)
			(layers "F.Cu" "F.Mask" "F.Paste")
			(net "GND")
		)
	)
)
